(kicad_pcb
	(version 20241229)
	(generator "pcbnew")
	(generator_version "9.0")
	(general
		(thickness 1.711)
		(legacy_teardrops no)
	)
	(paper "A4")
	(title_block
		(title "Antmicro Baseboard for Jetson AGX Thor")
		(date "2026-02-18")
		(rev "1.1.0")
		(company "Antmicro Ltd")
		(comment 1 "www.antmicro.com")
		(comment 9 "footprints 735-738 of 1170")
	)
	(layers
		(0 "F.Cu" signal)
		(4 "In1.Cu" signal)
		(6 "In2.Cu" signal)
		(8 "In3.Cu" signal)
		(10 "In4.Cu" jumper)
		(12 "In5.Cu" signal)
		(14 "In6.Cu" signal)
		(16 "In7.Cu" signal)
		(18 "In8.Cu" signal)
		(2 "B.Cu" signal)
		(9 "F.Adhes" user "F.Adhesive")
		(11 "B.Adhes" user "B.Adhesive")
		(13 "F.Paste" user)
		(15 "B.Paste" user)
		(5 "F.SilkS" user "F.Silkscreen")
		(7 "B.SilkS" user "B.Silkscreen")
		(1 "F.Mask" user)
		(3 "B.Mask" user)
		(17 "Dwgs.User" user "User.Drawings")
		(19 "Cmts.User" user "User.Comments")
		(21 "Eco1.User" user "User.Eco1")
		(23 "Eco2.User" user "User.Eco2")
		(25 "Edge.Cuts" user)
		(27 "Margin" user)
		(31 "F.CrtYd" user "F.Courtyard")
		(29 "B.CrtYd" user "B.Courtyard")
		(35 "F.Fab" user)
		(33 "B.Fab" user)
	)
	(footprint "antmicro-footprints:TP_SMD_0.75mm"
		(layer "B.Cu")
		(at 133 69.5 90)
		(property "Reference" "TP32"
			(at 0.53 -0.36 90)
			(layer "B.SilkS")
			(effects
				(font
					(size 0.7 0.7)
					(thickness 0.15)
				)
				(justify right top mirror)
			)
		)
		(property "Value" "TP_0.75mm_SMD"
			(at 0 -1.2 90)
			(layer "B.Fab")
			(effects
				(font
					(size 0.7 0.7)
					(thickness 0.15)
				)
				(justify right top mirror)
			)
		)
		(property "Description" "SMT test point"
			(at 0 0 90)
			(layer "B.Fab")
			(hide yes)
			(effects
				(font
					(size 1.27 1.27)
					(thickness 0.15)
				)
				(justify mirror)
			)
		)
		(property "MPN" ""
			(at 0 0 270)
			(unlocked yes)
			(layer "B.Fab")
			(hide yes)
			(effects
				(font
					(size 1 1)
					(thickness 0.15)
				)
				(justify mirror)
			)
		)
		(property "Manufacturer" ""
			(at 0 0 270)
			(unlocked yes)
			(layer "B.Fab")
			(hide yes)
			(effects
				(font
					(size 1 1)
					(thickness 0.15)
				)
				(justify mirror)
			)
		)
		(property "Author" "Antmicro"
			(at 0 0 270)
			(unlocked yes)
			(layer "B.Fab")
			(hide yes)
			(effects
				(font
					(size 1 1)
					(thickness 0.15)
				)
				(justify mirror)
			)
		)
		(property "License" "Apache-2.0"
			(at 0 0 270)
			(unlocked yes)
			(layer "B.Fab")
			(hide yes)
			(effects
				(font
					(size 1 1)
					(thickness 0.15)
				)
				(justify mirror)
			)
		)
		(sheetname "/SoM_Power/")
		(sheetfile "som_power.kicad_sch")
		(attr exclude_from_pos_files exclude_from_bom)
		(fp_circle
			(center 0 0)
			(end 0.475 0)
			(stroke
				(width 0.05)
				(type default)
			)
			(fill no)
			(layer "B.CrtYd")
		)
		(fp_text user "Author: Antmicro"
			(at -0.4 -3.901 90)
			(layer "B.Fab")
			(effects
				(font
					(size 0.7 0.7)
					(thickness 0.15)
				)
				(justify right top mirror)
			)
		)
		(fp_text user "License: Apache-2.0"
			(at -0.4 -5.101 90)
			(layer "B.Fab")
			(effects
				(font
					(size 0.7 0.7)
					(thickness 0.15)
				)
				(justify right top mirror)
			)
		)
		(fp_text user "${REFERENCE}"
			(at -0.4 -2.7 90)
			(layer "B.Fab")
			(effects
				(font
					(size 0.7 0.7)
					(thickness 0.15)
				)
				(justify right top mirror)
			)
		)
		(pad "1" smd circle
			(at 0 0 90)
			(size 0.75 0.75)
			(layers "B.Cu" "B.Mask")
			(net 601 "Net-(J1A-VM_INT_N)")
			(pinfunction "1")
			(pintype "passive")
		)
	)
	(footprint "antmicro-footprints:R_0402_1005Metric"
		(layer "B.Cu")
		(at 134.6 59 -90)
		(descr "Resistor SMD 0402")
		(tags "resistor SMD 0402")
		(property "Reference" "R242"
			(at -1.8 0.6 90)
			(layer "B.SilkS")
			(effects
				(font
					(size 0.7 0.7)
					(thickness 0.15)
				)
				(justify left bottom mirror)
			)
		)
		(property "Value" "R_200R_0402"
			(at -1.011843 -1.772046 90)
			(layer "B.Fab")
			(effects
				(font
					(size 0.7 0.7)
					(thickness 0.15)
				)
				(justify left bottom mirror)
			)
		)
		(property "Datasheet" "https://www.bourns.com/docs/product-datasheets/cr.pdf"
			(at 0 0 90)
			(layer "B.Fab")
			(hide yes)
			(effects
				(font
					(size 1.27 1.27)
					(thickness 0.15)
				)
				(justify mirror)
			)
		)
		(property "Description" "SMD Chip Resistor, 200 ohm, ± 1%, 62.5 mW, 0402 [1005 Metric], Thick Film, General Purpose"
			(at 0 0 90)
			(layer "B.Fab")
			(hide yes)
			(effects
				(font
					(size 1.27 1.27)
					(thickness 0.15)
				)
				(justify mirror)
			)
		)
		(property "Manufacturer" "Bourns"
			(at 0 0 90)
			(unlocked yes)
			(layer "B.Fab")
			(hide yes)
			(effects
				(font
					(size 1 1)
					(thickness 0.15)
				)
				(justify mirror)
			)
		)
		(property "MPN" "CR0402-FX-2000GLF"
			(at 0 0 90)
			(unlocked yes)
			(layer "B.Fab")
			(hide yes)
			(effects
				(font
					(size 1 1)
					(thickness 0.15)
				)
				(justify mirror)
			)
		)
		(property "Val" "200R"
			(at 0 0 90)
			(unlocked yes)
			(layer "B.Fab")
			(hide yes)
			(effects
				(font
					(size 1 1)
					(thickness 0.15)
				)
				(justify mirror)
			)
		)
		(property "License" "Apache-2.0"
			(at 0 0 90)
			(unlocked yes)
			(layer "B.Fab")
			(hide yes)
			(effects
				(font
					(size 1 1)
					(thickness 0.15)
				)
				(justify mirror)
			)
		)
		(property "Author" "Antmicro"
			(at 0 0 90)
			(unlocked yes)
			(layer "B.Fab")
			(hide yes)
			(effects
				(font
					(size 1 1)
					(thickness 0.15)
				)
				(justify mirror)
			)
		)
		(property "Tolerance" "1%"
			(at 0 0 90)
			(unlocked yes)
			(layer "B.Fab")
			(hide yes)
			(effects
				(font
					(size 1 1)
					(thickness 0.15)
				)
				(justify mirror)
			)
		)
		(sheetname "/Peripherals/")
		(sheetfile "peripherals.kicad_sch")
		(attr smd)
		(fp_poly
			(pts
				(xy -0.925 0.47) (xy -0.925 -0.47) (xy 0.925 -0.47) (xy 0.925 0.47)
			)
			(stroke
				(width 0.05)
				(type default)
			)
			(fill no)
			(layer "B.CrtYd")
		)
		(fp_poly
			(pts
				(xy -0.5 0.25) (xy -0.5 -0.25) (xy 0.5 -0.25) (xy 0.5 0.25)
			)
			(stroke
				(width 0.15)
				(type solid)
			)
			(fill no)
			(layer "B.Fab")
		)
		(fp_text user "${REFERENCE}"
			(at -0.95 -3.168 90)
			(layer "B.Fab")
			(effects
				(font
					(size 0.7 0.7)
					(thickness 0.15)
				)
				(justify left bottom mirror)
			)
		)
		(fp_text user "License: Apache-2.0"
			(at -0.949999 -5.169 90)
			(layer "B.Fab")
			(effects
				(font
					(size 0.7 0.7)
					(thickness 0.15)
				)
				(justify left bottom mirror)
			)
		)
		(fp_text user "Author: Antmicro"
			(at -0.95 -4.169 90)
			(layer "B.Fab")
			(effects
				(font
					(size 0.7 0.7)
					(thickness 0.15)
				)
				(justify left bottom mirror)
			)
		)
		(pad "1" smd roundrect
			(at -0.48 0 270)
			(size 0.59 0.64)
			(layers "B.Cu" "B.Mask" "B.Paste")
			(roundrect_rratio 0.25)
			(net 547 "Net-(D41-A)")
			(pintype "passive")
		)
		(pad "2" smd roundrect
			(at 0.48 0 270)
			(size 0.59 0.64)
			(layers "B.Cu" "B.Mask" "B.Paste")
			(roundrect_rratio 0.25)
			(net 838 "/Peripherals/I2C_CONN1_3V3")
			(pintype "passive")
		)
	)
	(footprint "antmicro-footprints:R_0402_1005Metric"
		(layer "B.Cu")
		(at 212.8 90.785001)
		(descr "Resistor SMD 0402")
		(tags "resistor SMD 0402")
		(property "Reference" "R128"
			(at -3.9 -0.3 0)
			(layer "B.SilkS")
			(effects
				(font
					(size 0.7 0.7)
					(thickness 0.15)
				)
				(justify right top mirror)
			)
		)
		(property "Value" "R_1k_0402"
			(at -1.011843 -1.772046 0)
			(layer "B.Fab")
			(effects
				(font
					(size 0.7 0.7)
					(thickness 0.15)
				)
				(justify right top mirror)
			)
		)
		(property "Datasheet" "https://www.bourns.com/docs/product-datasheets/cr.pdf"
			(at 0 0 0)
			(layer "B.Fab")
			(hide yes)
			(effects
				(font
					(size 1.27 1.27)
					(thickness 0.15)
				)
				(justify mirror)
			)
		)
		(property "Description" "SMD Chip Resistor, 1 kohm, ± 1%, 63 mW, 0402 [1005 Metric], Thick Film, General Purpose"
			(at 0 0 0)
			(layer "B.Fab")
			(hide yes)
			(effects
				(font
					(size 1.27 1.27)
					(thickness 0.15)
				)
				(justify mirror)
			)
		)
		(property "Manufacturer" "Bourns"
			(at 0 0 180)
			(unlocked yes)
			(layer "B.Fab")
			(hide yes)
			(effects
				(font
					(size 1 1)
					(thickness 0.15)
				)
				(justify mirror)
			)
		)
		(property "MPN" "CR0402-FX-1001GLF"
			(at 0 0 180)
			(unlocked yes)
			(layer "B.Fab")
			(hide yes)
			(effects
				(font
					(size 1 1)
					(thickness 0.15)
				)
				(justify mirror)
			)
		)
		(property "Val" "1k"
			(at 0 0 180)
			(unlocked yes)
			(layer "B.Fab")
			(hide yes)
			(effects
				(font
					(size 1 1)
					(thickness 0.15)
				)
				(justify mirror)
			)
		)
		(property "License" "Apache-2.0"
			(at 0 0 180)
			(unlocked yes)
			(layer "B.Fab")
			(hide yes)
			(effects
				(font
					(size 1 1)
					(thickness 0.15)
				)
				(justify mirror)
			)
		)
		(property "Author" "Antmicro"
			(at 0 0 180)
			(unlocked yes)
			(layer "B.Fab")
			(hide yes)
			(effects
				(font
					(size 1 1)
					(thickness 0.15)
				)
				(justify mirror)
			)
		)
		(property "Tolerance" "1%"
			(at 0 0 180)
			(unlocked yes)
			(layer "B.Fab")
			(hide yes)
			(effects
				(font
					(size 1 1)
					(thickness 0.15)
				)
				(justify mirror)
			)
		)
		(sheetname "/USB DP Alt mode/")
		(sheetfile "usb_dp.kicad_sch")
		(attr smd exclude_from_pos_files exclude_from_bom dnp)
		(fp_poly
			(pts
				(xy -0.925 0.47) (xy 0.925 0.47) (xy 0.925 -0.47) (xy -0.925 -0.47)
			)
			(stroke
				(width 0.05)
				(type default)
			)
			(fill no)
			(layer "B.CrtYd")
		)
		(fp_poly
			(pts
				(xy -0.5 0.25) (xy 0.5 0.25) (xy 0.5 -0.25) (xy -0.5 -0.25)
			)
			(stroke
				(width 0.15)
				(type solid)
			)
			(fill no)
			(layer "B.Fab")
		)
		(fp_text user "${REFERENCE}"
			(at -0.95 -3.168 0)
			(layer "B.Fab")
			(effects
				(font
					(size 0.7 0.7)
					(thickness 0.15)
				)
				(justify right top mirror)
			)
		)
		(fp_text user "License: Apache-2.0"
			(at -0.949999 -5.169 0)
			(layer "B.Fab")
			(effects
				(font
					(size 0.7 0.7)
					(thickness 0.15)
				)
				(justify right top mirror)
			)
		)
		(fp_text user "Author: Antmicro"
			(at -0.95 -4.169 0)
			(layer "B.Fab")
			(effects
				(font
					(size 0.7 0.7)
					(thickness 0.15)
				)
				(justify right top mirror)
			)
		)
		(pad "1" smd roundrect
			(at -0.48 0)
			(size 0.59 0.64)
			(layers "B.Cu" "B.Mask" "B.Paste")
			(roundrect_rratio 0.25)
			(net 963 "/USB DP Alt mode/USBC1_I2C_EN")
			(pintype "passive")
		)
		(pad "2" smd roundrect
			(at 0.48 0)
			(size 0.59 0.64)
			(layers "B.Cu" "B.Mask" "B.Paste")
			(roundrect_rratio 0.25)
			(net 2 "+3V3")
			(pintype "passive")
		)
	)
	(footprint "antmicro-footprints:Vishay_PowerPAK_1212-8_Single"
		(layer "B.Cu")
		(at 183.08 79.794 90)
		(descr "PowerPAK 1212-8 Single")
		(tags "Vishay PowerPAK 1212-8 Single")
		(property "Reference" "Q23"
			(at -0.006 1.92 90)
			(layer "B.SilkS")
			(effects
				(font
					(size 0.7 0.7)
					(thickness 0.15)
				)
				(justify right top mirror)
			)
		)
		(property "Value" "SISS05DN-T1-GE3"
			(at 0 -2.7 90)
			(layer "B.Fab")
			(effects
				(font
					(size 0.7 0.7)
					(thickness 0.15)
				)
				(justify right top mirror)
			)
		)
		(property "Datasheet" "https://www.vishay.com/docs/77029/siss05dn.pdf"
			(at 0 0 90)
			(layer "B.Fab")
			(hide yes)
			(effects
				(font
					(size 1.27 1.27)
					(thickness 0.15)
				)
				(justify mirror)
			)
		)
		(property "Description" "Power MOSFET, P Channel, 30 V, 108 A, 0.0035 ohm, PowerPAK 1212, Surface Mount"
			(at 0 0 90)
			(layer "B.Fab")
			(hide yes)
			(effects
				(font
					(size 1.27 1.27)
					(thickness 0.15)
				)
				(justify mirror)
			)
		)
		(property "MPN" "SISS05DN-T1-GE3"
			(at 0 0 270)
			(unlocked yes)
			(layer "B.Fab")
			(hide yes)
			(effects
				(font
					(size 1 1)
					(thickness 0.15)
				)
				(justify mirror)
			)
		)
		(property "Manufacturer" "Vishay"
			(at 0 0 270)
			(unlocked yes)
			(layer "B.Fab")
			(hide yes)
			(effects
				(font
					(size 1 1)
					(thickness 0.15)
				)
				(justify mirror)
			)
		)
		(property "Author" "Antmicro"
			(at 0 0 270)
			(unlocked yes)
			(layer "B.Fab")
			(hide yes)
			(effects
				(font
					(size 1 1)
					(thickness 0.15)
				)
				(justify mirror)
			)
		)
		(property "License" "Apache-2.0"
			(at 0 0 270)
			(unlocked yes)
			(layer "B.Fab")
			(hide yes)
			(effects
				(font
					(size 1 1)
					(thickness 0.15)
				)
				(justify mirror)
			)
		)
		(sheetname "/Power/")
		(sheetfile "power.kicad_sch")
		(attr smd exclude_from_pos_files exclude_from_bom dnp)
		(fp_line
			(start -1.635 -1.634)
			(end 1.634 -1.634)
			(stroke
				(width 0.15)
				(type solid)
			)
			(layer "B.SilkS")
		)
		(fp_line
			(start 1.634 -1.3)
			(end 1.634 -1.634)
			(stroke
				(width 0.15)
				(type solid)
			)
			(layer "B.SilkS")
		)
		(fp_line
			(start -1.635 -1.3)
			(end -1.635 -1.634)
			(stroke
				(width 0.15)
				(type solid)
			)
			(layer "B.SilkS")
		)
		(fp_line
			(start 1.648 1.651)
			(end 1.648 1.317)
			(stroke
				(width 0.15)
				(type solid)
			)
			(layer "B.SilkS")
		)
		(fp_line
			(start -1.651 1.651)
			(end -1.651 1.317)
			(stroke
				(width 0.15)
				(type solid)
			)
			(layer "B.SilkS")
		)
		(fp_line
			(start -1.651 1.651)
			(end 1.648 1.651)
			(stroke
				(width 0.15)
				(type solid)
			)
			(layer "B.SilkS")
		)
		(fp_circle
			(center -1.9 1.4)
			(end -1.85 1.4)
			(stroke
				(width 0.15)
				(type solid)
			)
			(fill yes)
			(layer "B.SilkS")
		)
		(fp_rect
			(start -2 1.8)
			(end 2 -1.798)
			(stroke
				(width 0.05)
				(type solid)
			)
			(fill no)
			(layer "B.CrtYd")
		)
		(fp_line
			(start -1.6425 1.4175)
			(end -1.4175 1.6425)
			(stroke
				(width 0.15)
				(type solid)
			)
			(layer "B.Fab")
		)
		(fp_rect
			(start -1.651 1.651)
			(end 1.648 -1.648)
			(stroke
				(width 0.15)
				(type solid)
			)
			(fill no)
			(layer "B.Fab")
		)
		(fp_text user "Author: Antmicro"
			(at -8 -5.9 90)
			(layer "B.Fab")
			(effects
				(font
					(size 0.7 0.7)
					(thickness 0.15)
				)
				(justify right top mirror)
			)
		)
		(fp_text user "${REFERENCE}"
			(at -8 -4.7 90)
			(layer "B.Fab")
			(effects
				(font
					(size 0.7 0.7)
					(thickness 0.15)
				)
				(justify right top mirror)
			)
		)
		(fp_text user "License: Apache-2.0"
			(at -8 -7.1 90)
			(layer "B.Fab")
			(effects
				(font
					(size 0.7 0.7)
					(thickness 0.15)
				)
				(justify right top mirror)
			)
		)
		(pad "1" smd rect
			(at -1.436 0.99 90)
			(size 0.99 0.405)
			(layers "B.Cu" "B.Mask" "B.Paste")
			(net 13 "VCC")
			(pinfunction "S")
			(pintype "passive")
		)
		(pad "2" smd rect
			(at -1.436 0.332 90)
			(size 0.99 0.405)
			(layers "B.Cu" "B.Mask" "B.Paste")
			(net 13 "VCC")
			(pinfunction "S")
			(pintype "passive")
		)
		(pad "3" smd rect
			(at -1.436 -0.33 90)
			(size 0.99 0.405)
			(layers "B.Cu" "B.Mask" "B.Paste")
			(net 13 "VCC")
			(pinfunction "S")
			(pintype "passive")
		)
		(pad "4" smd rect
			(at -1.436 -0.988 90)
			(size 0.99 0.405)
			(layers "B.Cu" "B.Mask" "B.Paste")
			(net 1201 "Net-(Q23-G)")
			(pinfunction "G")
			(pintype "input")
		)
		(pad "5" smd custom
			(at 0.557 0 90)
			(size 1.725 2.235)
			(layers "B.Cu" "B.Mask" "B.Paste")
			(net 525 "/Power/USBPD2_HV")
			(pinfunction "D")
			(pintype "passive")
			(zone_connect 2)
			(options
				(clearance outline)
				(anchor rect)
			)
			(primitives
				(gr_poly
					(pts
						(xy 0.8625 -0.1275) (xy 0.8625 0.1275) (xy 1.3725 0.1275) (xy 1.3725 0.5325) (xy 0.8625 0.5325)
						(xy 0.8625 0.7875) (xy 1.3725 0.7875) (xy 1.3725 1.195) (xy 0.6125 1.195) (xy 0.6125 -1.195) (xy 1.3725 -1.195)
						(xy 1.3725 -0.7875) (xy 0.8625 -0.7875) (xy 0.8625 -0.5325) (xy 1.3725 -0.5325) (xy 1.3725 -0.1275)
					)
					(width 0)
					(fill yes)
				)
			)
		)
	)
)
